# T6G (Grand Teton) — schematic parts with pin connectivity, parts 2650–2651 of 8303; source: Cadence DE-HDL packaged netlist (pstxprt.dat, pstxnet.dat, pstchip.dat)

J102  SCONN288_DDR506112002KQ  IO  pkg DDR288S_1-1VXC  page 104
  1  VIN_BULK0  POWER  = P12V_MEM_CPU1
  2  RFU0  TRI  = NC
  3  VIN_MGMT  POWER  = P3V3_AUX
  4  HSCL  IN  = I3C_SPD_DDRG_CPU1_SCL
  5  HSDA  BI  = I3C_SPD_DDRG_CPU1_SDA
  6  VSS0  POWER  = GND
  7  DQ0_A  BI  = M_G_CPU1_SA_DQ<0>
  8  VSS1  POWER  = GND
  9  DQ1_A  BI  = M_G_CPU1_SA_DQ<1>
  10  VSS2  POWER  = GND
  11  DQS0_A_T  BI  = M_G_CPU1_SA_DQS_DP<0>
  12  DQS0_A_C  BI  = M_G_CPU1_SA_DQS_DN<0>
  13  VSS3  POWER  = GND
  14  DQ4_A  BI  = M_G_CPU1_SA_DQ<4>
  15  VSS4  POWER  = GND
  16  DQ5_A  BI  = M_G_CPU1_SA_DQ<5>
  17  VSS5  POWER  = GND
  18  DQ8_A  BI  = M_G_CPU1_SA_DQ<8>
  19  VSS6  POWER  = GND
  20  DQ9_A  BI  = M_G_CPU1_SA_DQ<9>
  21  VSS7  POWER  = GND
  22  DQS1_A_T  BI  = M_G_CPU1_SA_DQS_DP<1>
  23  DQS1_A_C  BI  = M_G_CPU1_SA_DQS_DN<1>
  24  VSS8  POWER  = GND
  25  DQ12_A  BI  = M_G_CPU1_SA_DQ<12>
  26  VSS9  POWER  = GND
  27  DQ13_A  BI  = M_G_CPU1_SA_DQ<13>
  28  VSS10  POWER  = GND
  29  DQ16_A  BI  = M_G_CPU1_SA_DQ<16>
  30  VSS11  POWER  = GND
  31  DQ17_A  BI  = M_G_CPU1_SA_DQ<17>
  32  VSS12  POWER  = GND
  33  DQS2_A_T  BI  = M_G_CPU1_SA_DQS_DP<2>
  34  DQS2_A_C  BI  = M_G_CPU1_SA_DQS_DN<2>
  35  VSS13  POWER  = GND
  36  DQ20_A  BI  = M_G_CPU1_SA_DQ<20>
  37  VSS14  POWER  = GND
  38  DQ21_A  BI  = M_G_CPU1_SA_DQ<21>
  39  VSS15  POWER  = GND
  40  DQ24_A  BI  = M_G_CPU1_SA_DQ<24>
  41  VSS16  POWER  = GND
  42  DQ25_A  BI  = M_G_CPU1_SA_DQ<25>
  43  VSS17  POWER  = GND
  44  DQS3_A_T  BI  = M_G_CPU1_SA_DQS_DP<3>
  45  DQS3_A_C  BI  = M_G_CPU1_SA_DQS_DN<3>
  46  VSS18  POWER  = GND
  47  DQ28_A  BI  = M_G_CPU1_SA_DQ<28>
  48  VSS19  POWER  = GND
  49  DQ29_A  BI  = M_G_CPU1_SA_DQ<29>
  50  VSS20  POWER  = GND
  51  CB0_A  BI  = M_G_CPU1_SA_CB<0>
  52  VSS21  POWER  = GND
  53  CB1_A  BI  = M_G_CPU1_SA_CB<1>
  54  VSS22  POWER  = GND
  55  DQS4_A_T  BI  = M_G_CPU1_SA_DQS_DP<4>
  56  DQS4_A_C  BI  = M_G_CPU1_SA_DQS_DN<4>
  57  VSS23  POWER  = GND
  58  CB4_A  BI  = M_G_CPU1_SA_CB<4>
  59  VSS24  POWER  = GND
  60  CB5_A  BI  = M_G_CPU1_SA_CB<5>
  61  VSS25  POWER  = GND
  62  ALERT_N  OUT  = M_G_CPU1_ALERT_N
  63  VSS26  POWER  = GND
  64  CS0_A_N  IN  = M_G_CPU1_SA_CS_N<0>
  65  VSS27  POWER  = GND
  66  CA0_A  IN  = M_G_CPU1_SA_CA<0>
  67  VSS28  POWER  = GND
  68  CA2_A  IN  = M_G_CPU1_SA_CA<2>
  69  VSS29  POWER  = GND
  70  CA4_A  IN  = M_G_CPU1_SA_CA<4>
  71  VSS30  POWER  = GND
  72  CA6_A  IN  = M_G_CPU1_SA_CA<6>
  73  VSS31  POWER  = GND
  74  PAR_A  IN  = M_G_CPU1_SA_PAR
  75  VSS32  POWER  = GND
  76  CA0_B  IN  = M_G_CPU1_SB_CA<0>
  77  VSS33  POWER  = GND
  78  CA2_B  IN  = M_G_CPU1_SB_CA<2>
  79  VSS34  POWER  = GND
  80  CA4_B  IN  = M_G_CPU1_SB_CA<4>
  81  VSS35  POWER  = GND
  82  CA6_B  IN  = M_G_CPU1_SB_CA<6>
  83  VSS36  POWER  = GND
  84  CS0_B_N  IN  = M_G_CPU1_SB_CS_N<0>
  85  VSS37  POWER  = GND
  86  \lbd||rsp_a_n\  OUT  = M_G_CPU1_SA_RSP<0>
  87  \lbs||rsp_b_n\  OUT  = M_G_CPU1_SB_RSP<0>
  88  VSS38  POWER  = GND
  89  CB4_B  BI  = M_G_CPU1_SB_CB<4>
  90  VSS39  POWER  = GND
  91  CB5_B  BI  = M_G_CPU1_SB_CB<5>
  92  VSS40  POWER  = GND
  93  \dqs9_b_t||tdqs9_b_t||dbi4_b_n\  BI  = M_G_CPU1_SB_DQS_DP<9>
  94  \dqs9_b_c||tdqs9_b_c\  BI  = M_G_CPU1_SB_DQS_DN<9>
  95  VSS41  POWER  = GND
  96  CB0_B  BI  = M_G_CPU1_SB_CB<0>
  97  VSS42  POWER  = GND
  98  CB1_B  BI  = M_G_CPU1_SB_CB<1>
  99  VSS43  POWER  = GND
  100  DQ0_B  BI  = M_G_CPU1_SB_DQ<0>
  101  VSS44  POWER  = GND
  102  DQ1_B  BI  = M_G_CPU1_SB_DQ<1>
  103  VSS45  POWER  = GND
  104  DQS0_B_T  BI  = M_G_CPU1_SB_DQS_DP<0>
  105  DQS0_B_C  BI  = M_G_CPU1_SB_DQS_DN<0>
  106  VSS46  POWER  = GND
  107  DQ4_B  BI  = M_G_CPU1_SB_DQ<4>
  108  VSS47  POWER  = GND
  109  DQ5_B  BI  = M_G_CPU1_SB_DQ<5>
  110  VSS48  POWER  = GND
  111  DQ8_B  BI  = M_G_CPU1_SB_DQ<8>
  112  VSS49  POWER  = GND
  113  DQ9_B  BI  = M_G_CPU1_SB_DQ<9>
  114  VSS50  POWER  = GND
  115  DQS1_B_T  BI  = M_G_CPU1_SB_DQS_DP<1>
  116  DQS1_B_C  BI  = M_G_CPU1_SB_DQS_DN<1>
  117  VSS51  POWER  = GND
  118  DQ12_B  BI  = M_G_CPU1_SB_DQ<12>
  119  VSS52  POWER  = GND
  120  DQ13_B  BI  = M_G_CPU1_SB_DQ<13>
  121  VSS53  POWER  = GND
  122  DQ16_B  BI  = M_G_CPU1_SB_DQ<16>
  123  VSS54  POWER  = GND
  124  DQ17_B  BI  = M_G_CPU1_SB_DQ<17>
  125  VSS55  POWER  = GND
  126  DQS2_B_T  BI  = M_G_CPU1_SB_DQS_DP<2>
  127  DQS2_B_C  BI  = M_G_CPU1_SB_DQS_DN<2>
  128  VSS56  POWER  = GND
  129  DQ20_B  BI  = M_G_CPU1_SB_DQ<20>
  130  VSS57  POWER  = GND
  131  DQ21_B  BI  = M_G_CPU1_SB_DQ<21>
  132  VSS58  POWER  = GND
  133  DQ24_B  BI  = M_G_CPU1_SB_DQ<24>
  134  VSS59  POWER  = GND
  135  DQ25_B  BI  = M_G_CPU1_SB_DQ<25>
  136  VSS60  POWER  = GND
  137  DQS3_B_T  BI  = M_G_CPU1_SB_DQS_DP<3>
  138  DQS3_B_C  BI  = M_G_CPU1_SB_DQS_DN<3>
  139  VSS61  POWER  = GND
  140  DQ28_B  BI  = M_G_CPU1_SB_DQ<28>
  141  VSS62  POWER  = GND
  142  DQ29_B  BI  = M_G_CPU1_SB_DQ<29>
  143  VSS63  POWER  = GND
  144  RFU1  TRI  = NC
  145  VIN_BULK1  POWER  = P12V_MEM_CPU1
  146  VIN_BULK2  POWER  = P12V_MEM_CPU1
  147  \pwr_good||fail_n\  BI  = PWRGD_CHG_CPU1_DIMM0
  148  HAS  IN  = PD_CHG_CPU1_DIMM0_SAA
  149  RFU2  TRI  = NC
  150  RFU3  TRI  = NC
  151  VSS64  POWER  = GND
  152  DQ2_A  BI  = M_G_CPU1_SA_DQ<2>
  153  VSS65  POWER  = GND
  154  DQ3_A  BI  = M_G_CPU1_SA_DQ<3>
  155  VSS66  POWER  = GND
  156  \dqs5_a_c||tdqs5_a_c||dqs5_a_t||tdqs5_a_t\  BI  = M_G_CPU1_SA_DQS_DN<5>
  157  \dqs5_a_t||tdqs5_a_t\  BI  = M_G_CPU1_SA_DQS_DP<5>
  158  VSS67  POWER  = GND
  159  DQ6_A  BI  = M_G_CPU1_SA_DQ<6>
  160  VSS68  POWER  = GND
  161  DQ7_A  BI  = M_G_CPU1_SA_DQ<7>
  162  VSS69  POWER  = GND
  163  DQ10_A  BI  = M_G_CPU1_SA_DQ<10>
  164  VSS70  POWER  = GND
  165  DQ11_A  BI  = M_G_CPU1_SA_DQ<11>
  166  VSS71  POWER  = GND
  167  \dqs6_a_c||tdqs6_a_c||dqs6_a_t||tdqs6_a_t\  BI  = M_G_CPU1_SA_DQS_DN<6>
  168  \dqs6_a_t||tdqs6_a_t\  BI  = M_G_CPU1_SA_DQS_DP<6>
  169  VSS72  POWER  = GND
  170  DQ14_A  BI  = M_G_CPU1_SA_DQ<14>
  171  VSS73  POWER  = GND
  172  DQ15_A  BI  = M_G_CPU1_SA_DQ<15>
  173  VSS74  POWER  = GND
  174  DQ18_A  BI  = M_G_CPU1_SA_DQ<18>
  175  VSS75  POWER  = GND
  176  DQ19_A  BI  = M_G_CPU1_SA_DQ<19>
  177  VSS76  POWER  = GND
  178  \dqs7_a_c||tdqs7_a_c\  BI  = M_G_CPU1_SA_DQS_DN<7>
  179  \dqs7_a_t||tdqs7_a_t\  BI  = M_G_CPU1_SA_DQS_DP<7>
  180  VSS77  POWER  = GND
  181  DQ22_A  BI  = M_G_CPU1_SA_DQ<22>
  182  VSS78  POWER  = GND
  183  DQ23_A  BI  = M_G_CPU1_SA_DQ<23>
  184  VSS79  POWER  = GND
  185  DQ26_A  BI  = M_G_CPU1_SA_DQ<26>
  186  VSS80  POWER  = GND
  187  DQ27_A  BI  = M_G_CPU1_SA_DQ<27>
  188  VSS81  POWER  = GND
  189  \dqs8_a_c||tdqs8_a_c\  BI  = M_G_CPU1_SA_DQS_DN<8>
  190  \dqs8_a_t||tdqs8_a_t\  BI  = M_G_CPU1_SA_DQS_DP<8>
  191  VSS82  POWER  = GND
  192  DQ30_A  BI  = M_G_CPU1_SA_DQ<30>
  193  VSS83  POWER  = GND
  194  DQ31_A  BI  = M_G_CPU1_SA_DQ<31>
  195  VSS84  POWER  = GND
  196  CB2_A  BI  = M_G_CPU1_SA_CB<2>
  197  VSS85  POWER  = GND
  198  CB3_A  BI  = M_G_CPU1_SA_CB<3>
  199  VSS86  POWER  = GND
  200  \dqs9_a_c||tdqs9_a_c\  BI  = M_G_CPU1_SA_DQS_DN<9>
  201  \dqs9_a_t||tdqs9_a_t\  BI  = M_G_CPU1_SA_DQS_DP<9>
  202  VSS87  POWER  = GND
  203  CB6_A  BI  = M_G_CPU1_SA_CB<6>
  204  VSS88  POWER  = GND
  205  CB7_A  BI  = M_G_CPU1_SA_CB<7>
  206  VSS89  POWER  = GND
  207  RESET_N  IN  = M_G_CPU1_RESET_N
  208  VSS90  POWER  = GND
  209  CS1_A_N  IN  = M_G_CPU1_SA_CS_N<1>
  210  VSS91  POWER  = GND
  211  CA1_A  IN  = M_G_CPU1_SA_CA<1>
  212  VSS92  POWER  = GND
  213  CA3_A  IN  = M_G_CPU1_SA_CA<3>
  214  VSS93  POWER  = GND
  215  CA5_A  IN  = M_G_CPU1_SA_CA<5>
  216  VSS94  POWER  = GND
  217  CK_T  IN  = M_G_CPU1_CLK_DP<0>
  218  CK_C  IN  = M_G_CPU1_CLK_DN<0>
  219  VSS95  POWER  = GND
  220  RFU4  TRI  = NC
  221  CA1_B  IN  = M_G_CPU1_SB_CA<1>
  222  VSS96  POWER  = GND
  223  CA3_B  IN  = M_G_CPU1_SB_CA<3>
  224  VSS97  POWER  = GND
  225  CA5_B  IN  = M_G_CPU1_SB_CA<5>
  226  VSS98  POWER  = GND
  227  PAR_B  IN  = M_G_CPU1_SB_PAR
  228  VSS99  POWER  = GND
  229  CS1_B_N  IN  = M_G_CPU1_SB_CS_N<1>
  230  VSS100  POWER  = GND
  231  RFU5  TRI  = NC
  232  RFU6  TRI  = NC
  233  VSS101  POWER  = GND
  234  CB6_B  BI  = M_G_CPU1_SB_CB<6>
  235  VSS102  POWER  = GND
  236  CB7_B  BI  = M_G_CPU1_SB_CB<7>
  237  VSS103  POWER  = GND
  238  DQS4_B_C  BI  = M_G_CPU1_SB_DQS_DN<4>
  239  DQS4_B_T  BI  = M_G_CPU1_SB_DQS_DP<4>
  240  VSS104  POWER  = GND
  241  CB2_B  BI  = M_G_CPU1_SB_CB<2>
  242  VSS105  POWER  = GND
  243  CB3_B  BI  = M_G_CPU1_SB_CB<3>
  244  VSS106  POWER  = GND
  245  DQ2_B  BI  = M_G_CPU1_SB_DQ<2>
  246  VSS107  POWER  = GND
  247  DQ3_B  BI  = M_G_CPU1_SB_DQ<3>
  248  VSS108  POWER  = GND
  249  \dqs5_b_c||tdqs5_b_c\  BI  = M_G_CPU1_SB_DQS_DN<5>
  250  \dqs5_b_t||tdqs5_b_t\  BI  = M_G_CPU1_SB_DQS_DP<5>
  251  VSS109  POWER  = GND
  252  DQ6_B  BI  = M_G_CPU1_SB_DQ<6>
  253  VSS110  POWER  = GND
  254  DQ7_B  BI  = M_G_CPU1_SB_DQ<7>
  255  VSS111  POWER  = GND
  256  DQ10_B  BI  = M_G_CPU1_SB_DQ<10>
  257  VSS112  POWER  = GND
  258  DQ11_B  BI  = M_G_CPU1_SB_DQ<11>
  259  VSS113  POWER  = GND
  260  \dqs6_b_c||tdqs6_b_c\  BI  = M_G_CPU1_SB_DQS_DN<6>
  261  \dqs6_b_t||tdqs6_b_t\  BI  = M_G_CPU1_SB_DQS_DP<6>
  262  VSS114  POWER  = GND
  263  DQ14_B  BI  = M_G_CPU1_SB_DQ<14>
  264  VSS115  POWER  = GND
  265  DQ15_B  BI  = M_G_CPU1_SB_DQ<15>
  266  VSS116  POWER  = GND
  267  DQ18_B  BI  = M_G_CPU1_SB_DQ<18>
  268  VSS117  POWER  = GND
  269  DQ19_B  BI  = M_G_CPU1_SB_DQ<19>
  270  VSS118  POWER  = GND
  271  \dqs7_b_c||tdqs7_b_c\  BI  = M_G_CPU1_SB_DQS_DN<7>
  272  \dqs7_b_t||tdqs7_b_t\  BI  = M_G_CPU1_SB_DQS_DP<7>
  273  VSS119  POWER  = GND
  274  DQ22_B  BI  = M_G_CPU1_SB_DQ<22>
  275  VSS120  POWER  = GND
  276  DQ23_B  BI  = M_G_CPU1_SB_DQ<23>
  277  VSS121  POWER  = GND
  278  DQ26_B  BI  = M_G_CPU1_SB_DQ<26>
  279  VSS122  POWER  = GND
  280  DQ27_B  BI  = M_G_CPU1_SB_DQ<27>
  281  VSS123  POWER  = GND
  282  \dqs8_b_c||tdqs8_b_c\  BI  = M_G_CPU1_SB_DQS_DN<8>
  283  \dqs8_b_t||tdqs8_b_t\  BI  = M_G_CPU1_SB_DQS_DP<8>
  284  VSS124  POWER  = GND
  285  DQ30_B  BI  = M_G_CPU1_SB_DQ<30>
  286  VSS125  POWER  = GND
  287  DQ31_B  BI  = M_G_CPU1_SB_DQ<31>
  288  VSS126  POWER  = GND
  G1  G1  POWER  = GND
  G2  G2  POWER  = GND
  G3  G3  POWER  = GND

J105  CONN112_10137002101LF  CONN112_10137002-101LF IO  pkg HSD_F112D8_P2W1-2_RDH  page 115
  A1  A1  BI  = GPU_3V3IO_RSVD4
  A2  A2  BI  = GND
  A3  A3  BI  = GPU_WP_HW_CTRL_ISO_N
  A4  A4  BI  = GND
  A5  A5  BI  = GPU_3V3IO_RSVD3
  A6  A6  BI  = GND
  A7  A7  BI  = GPU_3V3IO_RSVD1
  A8  A8  BI  = GND
  B1  B1  BI  = GND
  B2  B2  BI  = P5E_CPU0_P2_RX_BUF_DN<9>
  B3  B3  BI  = GND
  B4  B4  BI  = P5E_CPU0_P2_RX_BUF_DN<11>
  B5  B5  BI  = GND
  B6  B6  BI  = P5E_CPU0_P2_RX_BUF_DN<13>
  B7  B7  BI  = GND
  B8  B8  BI  = P5E_CPU0_P2_RX_BUF_DN<15>
  C1  C1  BI  = P5E_CPU0_P2_RX_BUF_DN<8>
  C2  C2  BI  = P5E_CPU0_P2_RX_BUF_DP<9>
  C3  C3  BI  = P5E_CPU0_P2_RX_BUF_DN<10>
  C4  C4  BI  = P5E_CPU0_P2_RX_BUF_DP<11>
  C5  C5  BI  = P5E_CPU0_P2_RX_BUF_DN<12>
  C6  C6  BI  = P5E_CPU0_P2_RX_BUF_DP<13>
  C7  C7  BI  = P5E_CPU0_P2_RX_BUF_DN<14>
  C8  C8  BI  = P5E_CPU0_P2_RX_BUF_DP<15>
  D1  D1  BI  = P5E_CPU0_P2_RX_BUF_DP<8>
  D2  D2  BI  = GND
  D3  D3  BI  = P5E_CPU0_P2_RX_BUF_DP<10>
  D4  D4  BI  = GND
  D5  D5  BI  = P5E_CPU0_P2_RX_BUF_DP<12>
  D6  D6  BI  = GND
  D7  D7  BI  = P5E_CPU0_P2_RX_BUF_DP<14>
  D8  D8  BI  = GND
  E1  E1  BI  = GND
  E2  E2  BI  = P5E_CPU0_P3_RX_BUF_DN<9>
  E3  E3  BI  = GND
  E4  E4  BI  = P5E_CPU0_P3_RX_BUF_DN<11>
  E5  E5  BI  = GND
  E6  E6  BI  = P5E_CPU0_P3_RX_BUF_DN<13>
  E7  E7  BI  = GND
  E8  E8  BI  = P5E_CPU0_P3_RX_BUF_DN<15>
  F1  F1  BI  = P5E_CPU0_P3_RX_BUF_DN<8>
  F2  F2  BI  = P5E_CPU0_P3_RX_BUF_DP<9>
  F3  F3  BI  = P5E_CPU0_P3_RX_BUF_DN<10>
  F4  F4  BI  = P5E_CPU0_P3_RX_BUF_DP<11>
  F5  F5  BI  = P5E_CPU0_P3_RX_BUF_DN<12>
  F6  F6  BI  = P5E_CPU0_P3_RX_BUF_DP<13>
  F7  F7  BI  = P5E_CPU0_P3_RX_BUF_DN<14>
  F8  F8  BI  = P5E_CPU0_P3_RX_BUF_DP<15>
  G1  G1  BI  = P5E_CPU0_P3_RX_BUF_DP<8>
  G2  G2  BI  = GND
  G3  G3  BI  = P5E_CPU0_P3_RX_BUF_DP<10>
  G4  G4  BI  = GND
  G5  G5  BI  = P5E_CPU0_P3_RX_BUF_DP<12>
  G6  G6  BI  = GND
  G7  G7  BI  = P5E_CPU0_P3_RX_BUF_DP<14>
  G8  G8  BI  = GND
  H1  H1  BI  = GND
  H2  H2  BI  = P5E_CPU0_P2_TX_BUF_C_DN<9>
  H3  H3  BI  = GND
  H4  H4  BI  = P5E_CPU0_P2_TX_BUF_C_DN<11>
  H5  H5  BI  = GND
  H6  H6  BI  = P5E_CPU0_P2_TX_BUF_C_DN<13>
  H7  H7  BI  = GND
  H8  H8  BI  = P5E_CPU0_P2_TX_BUF_C_DN<15>
  I1  I1  BI  = P5E_CPU0_P2_TX_BUF_C_DN<8>
  I2  I2  BI  = P5E_CPU0_P2_TX_BUF_C_DP<9>
  I3  I3  BI  = P5E_CPU0_P2_TX_BUF_C_DN<10>
  I4  I4  BI  = P5E_CPU0_P2_TX_BUF_C_DP<11>
  I5  I5  BI  = P5E_CPU0_P2_TX_BUF_C_DN<12>
  I6  I6  BI  = P5E_CPU0_P2_TX_BUF_C_DP<13>
  I7  I7  BI  = P5E_CPU0_P2_TX_BUF_C_DN<14>
  I8  I8  BI  = P5E_CPU0_P2_TX_BUF_C_DP<15>
  J1  J1  BI  = P5E_CPU0_P2_TX_BUF_C_DP<8>
  J2  J2  BI  = GND
  J3  J3  BI  = P5E_CPU0_P2_TX_BUF_C_DP<10>
  J4  J4  BI  = GND
  J5  J5  BI  = P5E_CPU0_P2_TX_BUF_C_DP<12>
  J6  J6  BI  = GND
  J7  J7  BI  = P5E_CPU0_P2_TX_BUF_C_DP<14>
  J8  J8  BI  = GND
  K1  K1  BI  = GND
  K2  K2  BI  = P5E_CPU0_P3_TX_BUF_C_DN<9>
  K3  K3  BI  = GND
  K4  K4  BI  = P5E_CPU0_P3_TX_BUF_C_DN<11>
  K5  K5  BI  = GND
  K6  K6  BI  = P5E_CPU0_P3_TX_BUF_C_DN<13>
  K7  K7  BI  = GND
  K8  K8  BI  = P5E_CPU0_P3_TX_BUF_C_DN<15>
  L1  L1  BI  = P5E_CPU0_P3_TX_BUF_C_DN<8>
  L2  L2  BI  = P5E_CPU0_P3_TX_BUF_C_DP<9>
  L3  L3  BI  = P5E_CPU0_P3_TX_BUF_C_DN<10>
  L4  L4  BI  = P5E_CPU0_P3_TX_BUF_C_DP<11>
  L5  L5  BI  = P5E_CPU0_P3_TX_BUF_C_DN<12>
  L6  L6  BI  = P5E_CPU0_P3_TX_BUF_C_DP<13>
  L7  L7  BI  = P5E_CPU0_P3_TX_BUF_C_DN<14>
  L8  L8  BI  = P5E_CPU0_P3_TX_BUF_C_DP<15>
  M1  M1  BI  = P5E_CPU0_P3_TX_BUF_C_DP<8>
  M2  M2  BI  = GND
  M3  M3  BI  = P5E_CPU0_P3_TX_BUF_C_DP<10>
  M4  M4  BI  = GND
  M5  M5  BI  = P5E_CPU0_P3_TX_BUF_C_DP<12>
  M6  M6  BI  = GND
  M7  M7  BI  = P5E_CPU0_P3_TX_BUF_C_DP<14>
  M8  M8  BI  = GND
  N1  N1  BI  = GND
  N2  N2  BI  = FM_SWB_PWR_EN_R_BUF
  N3  N3  BI  = GND
  N4  N4  BI  = FM_SWB_BIC_READY_N
  N5  N5  BI  = GND
  N6  N6  BI  = RST_SWB_BIC_BUF_N
  N7  N7  BI  = GND
  N8  N8  BI  = RST_BMC_FROM_SWB_N
